(kicad_pcb
	(version 20260206)
	(generator "pcbnew")
	(generator_version "10.0")
	(general
		(thickness 1.6)
		(legacy_teardrops no)
	)
	(paper "A4")
	(title_block
		(title "baseboard — 13948-1b.1110WZS1818.brd")
		(comment 1 "Honey Badger (Wiwynn) / footprints 634-638 of 2523")
	)
	(layers
		(0 "F.Cu" signal "TOP")
		(4 "In1.Cu" signal "L2GND")
		(6 "In2.Cu" signal "L3")
		(8 "In3.Cu" signal "L4VCC")
		(10 "In4.Cu" signal "L5VCC")
		(12 "In5.Cu" signal "L6")
		(14 "In6.Cu" signal "L7GND")
		(2 "B.Cu" signal "BOTTOM")
		(9 "F.Adhes" user "F.Adhesive")
		(11 "B.Adhes" user "B.Adhesive")
		(13 "F.Paste" user "Package Geometry/Pastemask Top")
		(15 "B.Paste" user "Package Geometry/Pastemask Bottom")
		(5 "F.SilkS" user "Ref Des/Silkscreen Top")
		(7 "B.SilkS" user "Ref Des/Silkscreen Bottom")
		(1 "F.Mask" user "Board Geometry/Soldermask Top")
		(3 "B.Mask" user "Board Geometry/Soldermask Bottom")
		(17 "Dwgs.User" user "User.Drawings")
		(19 "Cmts.User" user "User.Comments")
		(21 "Eco1.User" user "User.Eco1")
		(23 "Eco2.User" user "User.Eco2")
		(25 "Edge.Cuts" user "Board Geometry/Outline")
		(27 "Margin" user)
		(31 "F.CrtYd" user "Package Geometry/Place Bound Top")
		(29 "B.CrtYd" user "Package Geometry/Place Bound Bottom")
		(35 "F.Fab" user "Ref Des/Assembly Top")
		(33 "B.Fab" user "Ref Des/Assembly Bottom")
	)
	(footprint ""
		(layer "F.Cu")
		(at 152.019 -55.499 90)
		(property "Reference" "SR700"
			(at 0 0 90)
			(layer "F.SilkS")
			(hide yes)
			(effects
				(font
					(size 1.27 1.27)
				)
			)
		)
		(property "Value" "10KR2F-2-GP"
			(at 0.064008 -3.993896 90)
			(unlocked yes)
			(layer "F.Fab")
			(hide yes)
			(effects
				(font
					(size 1.016 1.016)
					(thickness 0.1524)
				)
			)
		)
		(property "Device Type" "R402H16"
			(at 0.064008 -5.517896 90)
			(unlocked yes)
			(layer "F.Fab")
			(hide yes)
			(effects
				(font
					(size 1.016 1.016)
					(thickness 0.1524)
				)
			)
		)
		(duplicate_pad_numbers_are_jumpers no)
		(fp_line
			(start 0.508 -0.9398)
			(end -0.508 -0.9398)
			(stroke
				(width 0.1524)
				(type default)
			)
			(layer "F.SilkS")
		)
		(fp_line
			(start -0.508 -0.9398)
			(end -0.508 0.9398)
			(stroke
				(width 0.1524)
				(type default)
			)
			(layer "F.SilkS")
		)
		(fp_rect
			(start -0.508 0.9398)
			(end 0.508 -0.9398)
			(stroke
				(width 0)
				(type default)
			)
			(fill no)
			(layer "F.CrtYd")
		)
		(fp_rect
			(start -0.508 0.9398)
			(end 0.508 -0.9398)
			(stroke
				(width 0)
				(type default)
			)
			(fill no)
			(layer "F.Fab")
		)
		(pad "1" smd custom
			(at 0 -0.4445 90)
			(size 0.1397 0.1397)
			(layers "F.Cu" "F.Mask" "F.Paste")
			(net "XM_ADDR_6")
			(options
				(clearance outline)
				(anchor circle)
			)
			(primitives
				(gr_poly
					(pts
						(arc
							(start -0.1778 -0.2794)
							(mid -0.249642 -0.249642)
							(end -0.2794 -0.1778)
						)
						(arc
							(start -0.2794 0.1778)
							(mid -0.249642 0.249642)
							(end -0.1778 0.2794)
						)
						(arc
							(start 0.1778 0.2794)
							(mid 0.249642 0.249642)
							(end 0.2794 0.1778)
						)
						(arc
							(start 0.2794 -0.1778)
							(mid 0.249642 -0.249642)
							(end 0.1778 -0.2794)
						)
					)
					(width 0)
					(fill yes)
				)
			)
		)
		(pad "2" smd custom
			(at 0 0.4445 90)
			(size 0.1397 0.1397)
			(layers "F.Cu" "F.Mask" "F.Paste")
			(net "GND")
			(options
				(clearance outline)
				(anchor circle)
			)
			(primitives
				(gr_poly
					(pts
						(arc
							(start -0.1778 -0.2794)
							(mid -0.249642 -0.249642)
							(end -0.2794 -0.1778)
						)
						(arc
							(start -0.2794 0.1778)
							(mid -0.249642 0.249642)
							(end -0.1778 0.2794)
						)
						(arc
							(start 0.1778 0.2794)
							(mid 0.249642 0.249642)
							(end 0.2794 0.1778)
						)
						(arc
							(start 0.2794 -0.1778)
							(mid 0.249642 -0.249642)
							(end 0.1778 -0.2794)
						)
					)
					(width 0)
					(fill yes)
				)
			)
		)
	)
	(footprint ""
		(layer "F.Cu")
		(at 14.99997 -94.799912)
		(property "Reference" "CN1"
			(at 0 0 0)
			(layer "F.SilkS")
			(hide yes)
			(effects
				(font
					(size 1.27 1.27)
				)
			)
		)
		(property "Value" "MLX-CONN26-GP"
			(at -8.128 -14.6812 0)
			(unlocked yes)
			(layer "F.Fab")
			(hide yes)
			(effects
				(font
					(size 1.016 1.016)
					(thickness 0.1524)
				)
			)
		)
		(property "Device Type" "75586-0009"
			(at -8.128 -16.2052 0)
			(unlocked yes)
			(layer "F.Fab")
			(hide yes)
			(effects
				(font
					(size 1.016 1.016)
					(thickness 0.1524)
				)
			)
		)
		(duplicate_pad_numbers_are_jumpers no)
		(fp_line
			(start -7.0358 -8.8646)
			(end 7.0358 -8.8646)
			(stroke
				(width 0.1524)
				(type default)
			)
			(layer "F.SilkS")
		)
		(fp_line
			(start -7.0358 3.1496)
			(end -7.0358 -8.8646)
			(stroke
				(width 0.1524)
				(type default)
			)
			(layer "F.SilkS")
		)
		(fp_line
			(start 7.0358 -8.8646)
			(end 7.0358 3.1496)
			(stroke
				(width 0.1524)
				(type default)
			)
			(layer "F.SilkS")
		)
		(fp_line
			(start 7.0358 3.1496)
			(end -7.0358 3.1496)
			(stroke
				(width 0.1524)
				(type default)
			)
			(layer "F.SilkS")
		)
		(fp_rect
			(start -7.2898 3.4036)
			(end 7.2898 -9.1186)
			(stroke
				(width 0)
				(type default)
			)
			(fill no)
			(layer "F.CrtYd")
		)
		(fp_poly
			(pts
				(xy -7.2898 -9.1186) (xy 7.2898 -9.1186) (xy 7.2898 3.4036) (xy -7.2898 3.4036)
			)
			(stroke
				(width 0)
				(type default)
			)
			(fill no)
			(layer "F.Fab")
		)
		(pad "" np_thru_hole circle
			(at -5.99948 0)
			(size 0.254 0.254)
			(drill 1.5494)
			(layers "*.Cu" "*.Mask")
			(clearance 1.0033)
			(thermal_gap 1.0033)
		)
		(pad "" np_thru_hole circle
			(at 5.99948 0)
			(size 0.254 0.254)
			(drill 1.5494)
			(layers "*.Cu" "*.Mask")
			(clearance 1.0033)
			(thermal_gap 1.0033)
		)
		(pad "A1" smd oval
			(at -4.59994 -5.18033)
			(size 0.3556 1.8034)
			(layers "F.Cu" "F.Mask" "F.Paste")
			(net "GND")
		)
		(pad "A2" smd oval
			(at -3.79984 -5.18033)
			(size 0.3556 1.8034)
			(layers "F.Cu" "F.Mask" "F.Paste")
			(net "SAS_EXT_CONN_RX16_P")
		)
		(pad "A3" smd oval
			(at -2.99974 -5.18033)
			(size 0.3556 1.8034)
			(layers "F.Cu" "F.Mask" "F.Paste")
			(net "SAS_EXT_CONN_RX16_N")
		)
		(pad "A4" smd oval
			(at -2.19964 -5.18033)
			(size 0.3556 1.8034)
			(layers "F.Cu" "F.Mask" "F.Paste")
			(net "GND")
		)
		(pad "A5" smd oval
			(at -1.39954 -5.18033)
			(size 0.3556 1.8034)
			(layers "F.Cu" "F.Mask" "F.Paste")
			(net "SAS_EXT_CONN_RX17_P")
		)
		(pad "A6" smd oval
			(at -0.59944 -5.18033)
			(size 0.3556 1.8034)
			(layers "F.Cu" "F.Mask" "F.Paste")
			(net "SAS_EXT_CONN_RX17_N")
		)
		(pad "A7" smd oval
			(at 0.19939 -5.18033)
			(size 0.3556 1.8034)
			(layers "F.Cu" "F.Mask" "F.Paste")
			(net "GND")
		)
		(pad "A8" smd oval
			(at 0.99949 -5.18033)
			(size 0.3556 1.8034)
			(layers "F.Cu" "F.Mask" "F.Paste")
			(net "SAS_EXT_CONN_RX18_P")
		)
		(pad "A9" smd oval
			(at 1.79959 -5.18033)
			(size 0.3556 1.8034)
			(layers "F.Cu" "F.Mask" "F.Paste")
			(net "SAS_EXT_CONN_RX18_N")
		)
		(pad "A10" smd oval
			(at 2.59969 -5.18033)
			(size 0.3556 1.8034)
			(layers "F.Cu" "F.Mask" "F.Paste")
			(net "GND")
		)
		(pad "A11" smd oval
			(at 3.39979 -5.18033)
			(size 0.3556 1.8034)
			(layers "F.Cu" "F.Mask" "F.Paste")
			(net "SAS_EXT_CONN_RX19_P")
		)
		(pad "A12" smd oval
			(at 4.19989 -5.18033)
			(size 0.3556 1.8034)
			(layers "F.Cu" "F.Mask" "F.Paste")
			(net "SAS_EXT_CONN_RX19_N")
		)
		(pad "A13" smd oval
			(at 4.99999 -5.18033)
			(size 0.3556 1.8034)
			(layers "F.Cu" "F.Mask" "F.Paste")
			(net "GND")
		)
		(pad "B1" smd oval
			(at -4.99999 -7.68985)
			(size 0.3556 1.8034)
			(layers "F.Cu" "F.Mask" "F.Paste")
			(net "GND")
		)
		(pad "B2" smd oval
			(at -4.19989 -7.68985)
			(size 0.3556 1.8034)
			(layers "F.Cu" "F.Mask" "F.Paste")
			(net "IOC_RAID_TX_P4")
		)
		(pad "B3" smd oval
			(at -3.39979 -7.68985)
			(size 0.3556 1.8034)
			(layers "F.Cu" "F.Mask" "F.Paste")
			(net "IOC_RAID_TX_N4")
		)
		(pad "B4" smd oval
			(at -2.59969 -7.68985)
			(size 0.3556 1.8034)
			(layers "F.Cu" "F.Mask" "F.Paste")
			(net "GND")
		)
		(pad "B5" smd oval
			(at -1.79959 -7.68985)
			(size 0.3556 1.8034)
			(layers "F.Cu" "F.Mask" "F.Paste")
			(net "IOC_RAID_TX_P5")
		)
		(pad "B6" smd oval
			(at -0.99949 -7.68985)
			(size 0.3556 1.8034)
			(layers "F.Cu" "F.Mask" "F.Paste")
			(net "IOC_RAID_TX_N5")
		)
		(pad "B7" smd oval
			(at -0.19939 -7.68985)
			(size 0.3556 1.8034)
			(layers "F.Cu" "F.Mask" "F.Paste")
			(net "GND")
		)
		(pad "B8" smd oval
			(at 0.59944 -7.68985)
			(size 0.3556 1.8034)
			(layers "F.Cu" "F.Mask" "F.Paste")
			(net "IOC_RAID_TX_P6")
		)
		(pad "B9" smd oval
			(at 1.39954 -7.68985)
			(size 0.3556 1.8034)
			(layers "F.Cu" "F.Mask" "F.Paste")
			(net "IOC_RAID_TX_N6")
		)
		(pad "B10" smd oval
			(at 2.19964 -7.68985)
			(size 0.3556 1.8034)
			(layers "F.Cu" "F.Mask" "F.Paste")
			(net "GND")
		)
		(pad "B11" smd oval
			(at 2.99974 -7.68985)
			(size 0.3556 1.8034)
			(layers "F.Cu" "F.Mask" "F.Paste")
			(net "IOC_RAID_TX_P7")
		)
		(pad "B12" smd oval
			(at 3.79984 -7.68985)
			(size 0.3556 1.8034)
			(layers "F.Cu" "F.Mask" "F.Paste")
			(net "IOC_RAID_TX_N7")
		)
		(pad "B13" smd oval
			(at 4.59994 -7.68985)
			(size 0.3556 1.8034)
			(layers "F.Cu" "F.Mask" "F.Paste")
			(net "GND")
		)
		(zone
			(layer "F.Cu")
			(hatch none 0.5)
			(connect_pads
				(clearance 0)
			)
			(min_thickness 0.25)
			(keepout
				(tracks allowed)
				(vias not_allowed)
				(pads allowed)
				(copperpour not_allowed)
				(footprints allowed)
			)
			(placement
				(enabled no)
				(sheetname "")
			)
			(fill
				(thermal_gap 0.5)
				(thermal_bridge_width 0.5)
				(island_removal_mode 0)
			)
			(polygon
				(pts
					(xy 8.05053 -91.650312) (xy 9.88949 -91.650312) (xy 9.88949 -93.109542) (xy 8.05053 -93.109542)
				)
			)
		)
		(zone
			(layer "F.Cu")
			(hatch none 0.5)
			(connect_pads
				(clearance 0)
			)
			(min_thickness 0.25)
			(keepout
				(tracks not_allowed)
				(vias allowed)
				(pads allowed)
				(copperpour not_allowed)
				(footprints allowed)
			)
			(placement
				(enabled no)
				(sheetname "")
			)
			(fill
				(thermal_gap 0.5)
				(thermal_bridge_width 0.5)
				(island_removal_mode 0)
			)
			(polygon
				(pts
					(xy 8.05053 -91.650312) (xy 9.88949 -91.650312) (xy 9.88949 -93.109542) (xy 8.05053 -93.109542)
				)
			)
		)
		(zone
			(layer "F.Cu")
			(hatch none 0.5)
			(connect_pads
				(clearance 0)
			)
			(min_thickness 0.25)
			(keepout
				(tracks allowed)
				(vias not_allowed)
				(pads allowed)
				(copperpour not_allowed)
				(footprints allowed)
			)
			(placement
				(enabled no)
				(sheetname "")
			)
			(fill
				(thermal_gap 0.5)
				(thermal_bridge_width 0.5)
				(island_removal_mode 0)
			)
			(polygon
				(pts
					(xy 20.11045 -91.650312) (xy 21.94941 -91.650312) (xy 21.94941 -93.109542) (xy 20.11045 -93.109542)
				)
			)
		)
		(zone
			(layer "F.Cu")
			(hatch none 0.5)
			(connect_pads
				(clearance 0)
			)
			(min_thickness 0.25)
			(keepout
				(tracks not_allowed)
				(vias allowed)
				(pads allowed)
				(copperpour not_allowed)
				(footprints allowed)
			)
			(placement
				(enabled no)
				(sheetname "")
			)
			(fill
				(thermal_gap 0.5)
				(thermal_bridge_width 0.5)
				(island_removal_mode 0)
			)
			(polygon
				(pts
					(xy 20.11045 -91.650312) (xy 21.94941 -91.650312) (xy 21.94941 -93.109542) (xy 20.11045 -93.109542)
				)
			)
		)
		(zone
			(layers "F.Cu" "B.Cu" "In1.Cu" "In2.Cu" "In3.Cu" "In4.Cu" "In5.Cu" "In6.Cu")
			(hatch none 0.5)
			(connect_pads
				(clearance 0)
			)
			(min_thickness 0.25)
			(keepout
				(tracks not_allowed)
				(vias allowed)
				(pads allowed)
				(copperpour not_allowed)
				(footprints allowed)
			)
			(placement
				(enabled no)
				(sheetname "")
			)
			(fill
				(thermal_gap 0.5)
				(thermal_bridge_width 0.5)
				(island_removal_mode 0)
			)
			(polygon
				(pts
					(arc
						(start 10.07999 -94.799912)
						(mid 7.92099 -94.799912)
						(end 10.07999 -94.799912)
					)
				)
			)
		)
		(zone
			(layers "F.Cu" "B.Cu" "In1.Cu" "In2.Cu" "In3.Cu" "In4.Cu" "In5.Cu" "In6.Cu")
			(hatch none 0.5)
			(connect_pads
				(clearance 0)
			)
			(min_thickness 0.25)
			(keepout
				(tracks not_allowed)
				(vias allowed)
				(pads allowed)
				(copperpour not_allowed)
				(footprints allowed)
			)
			(placement
				(enabled no)
				(sheetname "")
			)
			(fill
				(thermal_gap 0.5)
				(thermal_bridge_width 0.5)
				(island_removal_mode 0)
			)
			(polygon
				(pts
					(arc
						(start 22.07895 -94.799912)
						(mid 19.91995 -94.799912)
						(end 22.07895 -94.799912)
					)
				)
			)
		)
	)
	(footprint ""
		(layer "F.Cu")
		(at 81.024222 -114.394742 -90)
		(property "Reference" "SC1284"
			(at 0 0 270)
			(layer "F.SilkS")
			(hide yes)
			(effects
				(font
					(size 1.27 1.27)
				)
			)
		)
		(property "Value" "SCD1U16V2KX-3GP"
			(at 1.1811 -2.7051 270)
			(unlocked yes)
			(layer "F.Fab")
			(hide yes)
			(effects
				(font
					(size 1.016 1.016)
					(thickness 0.1524)
				)
			)
		)
		(property "Device Type" "C402H22"
			(at 1.1811 -4.2291 270)
			(unlocked yes)
			(layer "F.Fab")
			(hide yes)
			(effects
				(font
					(size 1.016 1.016)
					(thickness 0.1524)
				)
			)
		)
		(duplicate_pad_numbers_are_jumpers no)
		(fp_rect
			(start -0.4318 0.9525)
			(end 0.4318 -0.9525)
			(stroke
				(width 0)
				(type default)
			)
			(fill no)
			(layer "F.CrtYd")
		)
		(fp_rect
			(start -0.4318 0.9525)
			(end 0.4318 -0.9525)
			(stroke
				(width 0)
				(type default)
			)
			(fill no)
			(layer "F.Fab")
		)
		(pad "1" smd custom
			(at 0 -0.4445 270)
			(size 0.1524 0.1524)
			(layers "F.Cu" "F.Mask" "F.Paste")
			(net "EXP_I2C_VREF_1")
			(options
				(clearance outline)
				(anchor circle)
			)
			(primitives
				(gr_poly
					(pts
						(arc
							(start 0.3048 -0.2032)
							(mid 0.275042 -0.275042)
							(end 0.2032 -0.3048)
						)
						(arc
							(start -0.2032 -0.3048)
							(mid -0.275042 -0.275042)
							(end -0.3048 -0.2032)
						)
						(arc
							(start -0.3048 0.2032)
							(mid -0.275042 0.275042)
							(end -0.2032 0.3048)
						)
						(arc
							(start 0.2032 0.3048)
							(mid 0.275042 0.275042)
							(end 0.3048 0.2032)
						)
					)
					(width 0)
					(fill yes)
				)
			)
		)
		(pad "2" smd custom
			(at 0 0.4445 270)
			(size 0.1524 0.1524)
			(layers "F.Cu" "F.Mask" "F.Paste")
			(net "GND")
			(options
				(clearance outline)
				(anchor circle)
			)
			(primitives
				(gr_poly
					(pts
						(arc
							(start 0.3048 -0.2032)
							(mid 0.275042 -0.275042)
							(end 0.2032 -0.3048)
						)
						(arc
							(start -0.2032 -0.3048)
							(mid -0.275042 -0.275042)
							(end -0.3048 -0.2032)
						)
						(arc
							(start -0.3048 0.2032)
							(mid -0.275042 0.275042)
							(end -0.2032 0.3048)
						)
						(arc
							(start 0.2032 0.3048)
							(mid 0.275042 0.275042)
							(end 0.3048 0.2032)
						)
					)
					(width 0)
					(fill yes)
				)
			)
		)
	)
	(footprint ""
		(layer "F.Cu")
		(at 344.021918 -157.838648)
		(property "Reference" "R227"
			(at 0 0 0)
			(layer "F.SilkS")
			(hide yes)
			(effects
				(font
					(size 1.27 1.27)
				)
			)
		)
		(property "Value" "4K7R2F-GP"
			(at 0.064008 -3.993896 0)
			(unlocked yes)
			(layer "F.Fab")
			(hide yes)
			(effects
				(font
					(size 1.016 1.016)
					(thickness 0.1524)
				)
			)
		)
		(property "Device Type" "R402H16"
			(at 0.064008 -5.517896 0)
			(unlocked yes)
			(layer "F.Fab")
			(hide yes)
			(effects
				(font
					(size 1.016 1.016)
					(thickness 0.1524)
				)
			)
		)
		(duplicate_pad_numbers_are_jumpers no)
		(fp_line
			(start -0.508 -0.9398)
			(end -0.508 0.9398)
			(stroke
				(width 0.1524)
				(type default)
			)
			(layer "F.SilkS")
		)
		(fp_line
			(start 0.508 -0.9398)
			(end -0.508 -0.9398)
			(stroke
				(width 0.1524)
				(type default)
			)
			(layer "F.SilkS")
		)
		(fp_rect
			(start -0.508 0.9398)
			(end 0.508 -0.9398)
			(stroke
				(width 0)
				(type default)
			)
			(fill no)
			(layer "F.CrtYd")
		)
		(fp_rect
			(start -0.508 0.9398)
			(end 0.508 -0.9398)
			(stroke
				(width 0)
				(type default)
			)
			(fill no)
			(layer "F.Fab")
		)
		(pad "1" smd custom
			(at 0 -0.4445)
			(size 0.1397 0.1397)
			(layers "F.Cu" "F.Mask" "F.Paste")
			(net "P3V3_STBY")
			(options
				(clearance outline)
				(anchor circle)
			)
			(primitives
				(gr_poly
					(pts
						(arc
							(start -0.1778 -0.2794)
							(mid -0.249642 -0.249642)
							(end -0.2794 -0.1778)
						)
						(arc
							(start -0.2794 0.1778)
							(mid -0.249642 0.249642)
							(end -0.1778 0.2794)
						)
						(arc
							(start 0.1778 0.2794)
							(mid 0.249642 0.249642)
							(end 0.2794 0.1778)
						)
						(arc
							(start 0.2794 -0.1778)
							(mid 0.249642 -0.249642)
							(end 0.1778 -0.2794)
						)
					)
					(width 0)
					(fill yes)
				)
			)
		)
		(pad "2" smd custom
			(at 0 0.4445)
			(size 0.1397 0.1397)
			(layers "F.Cu" "F.Mask" "F.Paste")
			(net "USB_EN_1")
			(options
				(clearance outline)
				(anchor circle)
			)
			(primitives
				(gr_poly
					(pts
						(arc
							(start -0.1778 -0.2794)
							(mid -0.249642 -0.249642)
							(end -0.2794 -0.1778)
						)
						(arc
							(start -0.2794 0.1778)
							(mid -0.249642 0.249642)
							(end -0.1778 0.2794)
						)
						(arc
							(start 0.1778 0.2794)
							(mid 0.249642 0.249642)
							(end 0.2794 0.1778)
						)
						(arc
							(start 0.2794 -0.1778)
							(mid 0.249642 -0.249642)
							(end 0.1778 -0.2794)
						)
					)
					(width 0)
					(fill yes)
				)
			)
		)
	)
	(footprint ""
		(layer "F.Cu")
		(at 190.554864 -31.695136 180)
		(property "Reference" "C224"
			(at 0 0 180)
			(layer "F.SilkS")
			(hide yes)
			(effects
				(font
					(size 1.27 1.27)
				)
			)
		)
		(property "Value" "SCD01U16V2KX-3GP"
			(at 1.1811 -2.7051 180)
			(unlocked yes)
			(layer "F.Fab")
			(hide yes)
			(effects
				(font
					(size 1.016 1.016)
					(thickness 0.1524)
				)
			)
		)
		(property "Device Type" "C402H22"
			(at 1.1811 -4.2291 180)
			(unlocked yes)
			(layer "F.Fab")
			(hide yes)
			(effects
				(font
					(size 1.016 1.016)
					(thickness 0.1524)
				)
			)
		)
		(duplicate_pad_numbers_are_jumpers no)
		(fp_rect
			(start -0.4318 0.9525)
			(end 0.4318 -0.9525)
			(stroke
				(width 0)
				(type default)
			)
			(fill no)
			(layer "F.CrtYd")
		)
		(fp_rect
			(start -0.4318 0.9525)
			(end 0.4318 -0.9525)
			(stroke
				(width 0)
				(type default)
			)
			(fill no)
			(layer "F.Fab")
		)
		(pad "1" smd custom
			(at 0 -0.4445 180)
			(size 0.1524 0.1524)
			(layers "F.Cu" "F.Mask" "F.Paste")
			(net "PHY_DVDD")
			(options
				(clearance outline)
				(anchor circle)
			)
			(primitives
				(gr_poly
					(pts
						(arc
							(start 0.3048 -0.2032)
							(mid 0.275042 -0.275042)
							(end 0.2032 -0.3048)
						)
						(arc
							(start -0.2032 -0.3048)
							(mid -0.275042 -0.275042)
							(end -0.3048 -0.2032)
						)
						(arc
							(start -0.3048 0.2032)
							(mid -0.275042 0.275042)
							(end -0.2032 0.3048)
						)
						(arc
							(start 0.2032 0.3048)
							(mid 0.275042 0.275042)
							(end 0.3048 0.2032)
						)
					)
					(width 0)
					(fill yes)
				)
			)
		)
		(pad "2" smd custom
			(at 0 0.4445 180)
			(size 0.1524 0.1524)
			(layers "F.Cu" "F.Mask" "F.Paste")
			(net "GND")
			(options
				(clearance outline)
				(anchor circle)
			)
			(primitives
				(gr_poly
					(pts
						(arc
							(start 0.3048 -0.2032)
							(mid 0.275042 -0.275042)
							(end 0.2032 -0.3048)
						)
						(arc
							(start -0.2032 -0.3048)
							(mid -0.275042 -0.275042)
							(end -0.3048 -0.2032)
						)
						(arc
							(start -0.3048 0.2032)
							(mid -0.275042 0.275042)
							(end -0.2032 0.3048)
						)
						(arc
							(start 0.2032 0.3048)
							(mid 0.275042 0.275042)
							(end 0.3048 0.2032)
						)
					)
					(width 0)
					(fill yes)
				)
			)
		)
	)
)
